# T6G (Grand Teton) — schematic netlist excerpt (pin names and nets, part order shuffled) for the footprints in the layout excerpt that follows; sources: Cadence DE-HDL packaged netlist, KiCad conversion of 04192023_DAF0TMB3IC0_F0TG_MB_C_brd_V02_OCP.brd

PR217  Q_RES  0 5% CHIP  pkg 0402LF  page 217 : A = SVID_PVDDCR_CPU1_P1_SVTI ; B = GND
PC2213  Q_CAP  0.01UF 50V 10% EMPTY  pkg C0402  page 146 : A = P3V3_E1S_0_R ; B = P3V3_E1S_GATE_0

(kicad_pcb
	(version 20260206)
	(generator "pcbnew")
	(generator_version "10.0")
	(general
		(thickness 1.6)
		(legacy_teardrops no)
	)
	(paper "A4")
	(title_block
		(title "04192023_DAF0TMB3IC0_F0TG_MB_C_brd_V02_OCP.brd")
		(comment 1 "Grand Teton / footprints 1992-1993 of 8354")
	)
	(layers
		(0 "F.Cu" signal "TOP")
		(4 "In1.Cu" signal "GND")
		(6 "In2.Cu" signal "IN1")
		(8 "In3.Cu" signal "GND1")
		(10 "In4.Cu" signal "IN2")
		(12 "In5.Cu" signal "GND2")
		(14 "In6.Cu" signal "IN3")
		(16 "In7.Cu" signal "GND3")
		(18 "In8.Cu" signal "VCC")
		(20 "In9.Cu" signal "VCC1")
		(22 "In10.Cu" signal "GND4")
		(24 "In11.Cu" signal "IN4")
		(26 "In12.Cu" signal "GND5")
		(28 "In13.Cu" signal "IN5")
		(30 "In14.Cu" signal "GND6")
		(32 "In15.Cu" signal "IN6")
		(34 "In16.Cu" signal "GND7")
		(2 "B.Cu" signal "BOTTOM")
		(9 "F.Adhes" user "F.Adhesive")
		(11 "B.Adhes" user "B.Adhesive")
		(13 "F.Paste" user "Package Geometry/Pastemask Top")
		(15 "B.Paste" user "Package Geometry/Pastemask Bottom")
		(5 "F.SilkS" user "Ref Des/Silkscreen Top")
		(7 "B.SilkS" user "Ref Des/Silkscreen Bottom")
		(1 "F.Mask" user "Board Geometry/Soldermask Top")
		(3 "B.Mask" user "Board Geometry/Soldermask Bottom")
		(17 "Dwgs.User" user "User.Drawings")
		(19 "Cmts.User" user "User.Comments")
		(21 "Eco1.User" user "User.Eco1")
		(23 "Eco2.User" user "User.Eco2")
		(25 "Edge.Cuts" user "Board Geometry/Outline")
		(27 "Margin" user)
		(31 "F.CrtYd" user "Package Geometry/Place Bound Top")
		(29 "B.CrtYd" user "Package Geometry/Place Bound Bottom")
		(35 "F.Fab" user "Ref Des/Assembly Top")
		(33 "B.Fab" user "Ref Des/Assembly Bottom")
	)
	(footprint ""
		(layer "F.Cu")
		(at 223.378522 -74.510138 180)
		(property "Reference" "PC2213"
			(at 0 0 180)
			(layer "F.SilkS")
			(hide yes)
			(effects
				(font
					(size 1.27 1.27)
				)
			)
		)
		(property "Value" ""
			(at 0 0 180)
			(layer "F.Fab")
			(effects
				(font
					(size 1.27 1.27)
				)
			)
		)
		(duplicate_pad_numbers_are_jumpers no)
		(fp_line
			(start 0.7874 0.4064)
			(end -0.7874 0.4064)
			(stroke
				(width 0.1524)
				(type default)
			)
			(layer "F.SilkS")
		)
		(fp_line
			(start 0.7874 -0.4064)
			(end 0.7874 0.4064)
			(stroke
				(width 0.1524)
				(type default)
			)
			(layer "F.SilkS")
		)
		(fp_line
			(start -0.7874 0.4064)
			(end -0.7874 -0.4064)
			(stroke
				(width 0.1524)
				(type default)
			)
			(layer "F.SilkS")
		)
		(fp_line
			(start -0.7874 -0.4064)
			(end 0.7874 -0.4064)
			(stroke
				(width 0.1524)
				(type default)
			)
			(layer "F.SilkS")
		)
		(fp_line
			(start 0.67945 0.3048)
			(end 0.120396 0.3048)
			(stroke
				(width 0.1)
				(type default)
			)
			(layer "F.Fab")
		)
		(fp_line
			(start 0.67945 -0.3048)
			(end 0.67945 0.3048)
			(stroke
				(width 0.1)
				(type default)
			)
			(layer "F.Fab")
		)
		(fp_line
			(start 0.12065 -0.2794)
			(end 0.12065 -0.3048)
			(stroke
				(width 0.1)
				(type default)
			)
			(layer "F.Fab")
		)
		(fp_line
			(start 0.12065 -0.3048)
			(end 0.67945 -0.3048)
			(stroke
				(width 0.1)
				(type default)
			)
			(layer "F.Fab")
		)
		(fp_line
			(start 0.120396 0.3048)
			(end 0.120396 0.2794)
			(stroke
				(width 0.1)
				(type default)
			)
			(layer "F.Fab")
		)
		(fp_line
			(start 0.120396 0.2794)
			(end -0.12065 0.2794)
			(stroke
				(width 0.1)
				(type default)
			)
			(layer "F.Fab")
		)
		(fp_line
			(start -0.12065 0.3048)
			(end -0.67945 0.3048)
			(stroke
				(width 0.1)
				(type default)
			)
			(layer "F.Fab")
		)
		(fp_line
			(start -0.12065 0.2794)
			(end -0.12065 0.3048)
			(stroke
				(width 0.1)
				(type default)
			)
			(layer "F.Fab")
		)
		(fp_line
			(start -0.12065 -0.2794)
			(end 0.12065 -0.2794)
			(stroke
				(width 0.1)
				(type default)
			)
			(layer "F.Fab")
		)
		(fp_line
			(start -0.12065 -0.305054)
			(end -0.12065 -0.2794)
			(stroke
				(width 0.1)
				(type default)
			)
			(layer "F.Fab")
		)
		(fp_line
			(start -0.67945 0.3048)
			(end -0.67945 -0.305054)
			(stroke
				(width 0.1)
				(type default)
			)
			(layer "F.Fab")
		)
		(fp_line
			(start -0.67945 -0.305054)
			(end -0.12065 -0.305054)
			(stroke
				(width 0.1)
				(type default)
			)
			(layer "F.Fab")
		)
		(pad "1" smd circle
			(at -0.40005 0 180)
			(size 0 0)
			(layers "F.Cu" "F.Mask" "F.Paste")
			(net "P3V3_E1S_0_R")
		)
		(pad "2" smd circle
			(at 0.40005 0 180)
			(size 0 0)
			(layers "F.Cu" "F.Mask" "F.Paste")
			(net "P3V3_E1S_GATE_0")
		)
	)
	(footprint ""
		(layer "F.Cu")
		(at 22.479 -357.632 180)
		(property "Reference" "PR217"
			(at 0 0 180)
			(layer "F.SilkS")
			(hide yes)
			(effects
				(font
					(size 1.27 1.27)
				)
			)
		)
		(property "Value" ""
			(at 0 0 180)
			(layer "F.Fab")
			(effects
				(font
					(size 1.27 1.27)
				)
			)
		)
		(duplicate_pad_numbers_are_jumpers no)
		(fp_line
			(start 0.7874 0.4064)
			(end -0.7874 0.4064)
			(stroke
				(width 0.1524)
				(type default)
			)
			(layer "F.SilkS")
		)
		(fp_line
			(start 0.7874 -0.4064)
			(end 0.7874 0.4064)
			(stroke
				(width 0.1524)
				(type default)
			)
			(layer "F.SilkS")
		)
		(fp_line
			(start -0.7874 0.4064)
			(end -0.7874 -0.4064)
			(stroke
				(width 0.1524)
				(type default)
			)
			(layer "F.SilkS")
		)
		(fp_line
			(start -0.7874 -0.4064)
			(end 0.7874 -0.4064)
			(stroke
				(width 0.1524)
				(type default)
			)
			(layer "F.SilkS")
		)
		(fp_line
			(start 0.67945 0.3048)
			(end 0.120396 0.3048)
			(stroke
				(width 0.1)
				(type default)
			)
			(layer "F.Fab")
		)
		(fp_line
			(start 0.67945 -0.3048)
			(end 0.67945 0.3048)
			(stroke
				(width 0.1)
				(type default)
			)
			(layer "F.Fab")
		)
		(fp_line
			(start 0.12065 -0.2794)
			(end 0.12065 -0.3048)
			(stroke
				(width 0.1)
				(type default)
			)
			(layer "F.Fab")
		)
		(fp_line
			(start 0.12065 -0.3048)
			(end 0.67945 -0.3048)
			(stroke
				(width 0.1)
				(type default)
			)
			(layer "F.Fab")
		)
		(fp_line
			(start 0.120396 0.3048)
			(end 0.120396 0.2794)
			(stroke
				(width 0.1)
				(type default)
			)
			(layer "F.Fab")
		)
		(fp_line
			(start 0.120396 0.2794)
			(end -0.12065 0.2794)
			(stroke
				(width 0.1)
				(type default)
			)
			(layer "F.Fab")
		)
		(fp_line
			(start -0.12065 0.3048)
			(end -0.67945 0.3048)
			(stroke
				(width 0.1)
				(type default)
			)
			(layer "F.Fab")
		)
		(fp_line
			(start -0.12065 0.2794)
			(end -0.12065 0.3048)
			(stroke
				(width 0.1)
				(type default)
			)
			(layer "F.Fab")
		)
		(fp_line
			(start -0.12065 -0.2794)
			(end 0.12065 -0.2794)
			(stroke
				(width 0.1)
				(type default)
			)
			(layer "F.Fab")
		)
		(fp_line
			(start -0.12065 -0.305054)
			(end -0.12065 -0.2794)
			(stroke
				(width 0.1)
				(type default)
			)
			(layer "F.Fab")
		)
		(fp_line
			(start -0.67945 0.3048)
			(end -0.67945 -0.305054)
			(stroke
				(width 0.1)
				(type default)
			)
			(layer "F.Fab")
		)
		(fp_line
			(start -0.67945 -0.305054)
			(end -0.12065 -0.305054)
			(stroke
				(width 0.1)
				(type default)
			)
			(layer "F.Fab")
		)
		(pad "1" smd circle
			(at -0.40005 0 180)
			(size 0 0)
			(layers "F.Cu" "F.Mask" "F.Paste")
			(net "SVID_PVDDCR_CPU1_P1_SVTI")
		)
		(pad "2" smd circle
			(at 0.40005 0 180)
			(size 0 0)
			(layers "F.Cu" "F.Mask" "F.Paste")
			(net "GND")
		)
	)
)
